#ISCELL
  pure_quanta quanta_title_block_c *
  *
#CELL
  pure_quanta socket4677_azif0045p001c01cs *
  page36_i1
#ISCELL
  logical_power vcc_core *
  page36_i2
#ISCELL
  logical_power vcc_core *
  page36_i3
#ISCELL
  logical_power vcc_core *
  page36_i5
#ISCELL
  logical_power vcc_core *
  page36_i6
#CELL
  pure_quanta socket4677_azif0045p001c01cs *
  page36_i7
